FILE_TYPE = CONNECTIVITY;
{Allegro Design Entry HDL 17.2-2016 S081 (4005846) 1/11/2022}
"PAGE_NUMBER" = 177;
0"NC";
1"GND\g";
2"GND\g";
3"GND\g";
4"GND\g";
5"GND\g";
6"GND\g";
7"GND\g";
8"GND\g";
9"GND\g";
10"GND\g";
11"SW_PVDDCR_CPU1_P0_BOOT4_R";
12"GND\g";
13"SW_PVDDCR_CPU1_P0_BOOT3_R";
14"GND\g";
15"SW_PVDDCR_CPU1_P0_SW3";
16"SW_PVDDCR_CPU1_P0_BOOT3";
17"SW_PVDDCR_CPU1_P0_BOOTR3";
18"GND\g";
19"PVDDCR_CPU1_P0\g";
20"GND\g";
21"PVDDCR_CPU1_P0\g";
22"SW_P12V_STBY_PVDDCR_CPU1_P0_FLT\g";
23"SW_P12V_STBY_PVDDCR_CPU1_P0_FLT\g";
24"GND\g";
25"PVDDCR_CPU1_P0_PVCC\g";
26"PVDDCR_CPU1_P0_PVCC\g";
27"GND\g";
28"GND\g";
29"SW_PVDDCR_CPU1_P0_BOOTR4";
30"SW_PVDDCR_CPU1_P0_SW4";
31"PVDDCR_CPU1_P0_VOS4";
32"NC_PVDDCR_CPU1_P0_GL2_4";
33"NC_PVDDCR_CPU1_P0_GL1_4";
34"SW_PVDDCR_CPU1_P0_BOOT4";
35"PVDDCR_CPU1_P0_VCC4";
36"PVDDCR_CPU1_P0_VCCS"CDS_PHYS_NET_NAME"PVCCIN_CPU0_VREF";
37"PVDDCR_CPU1_P0_LSET4";
38"PVDDCR_CPU1_P0_PWM3";
39"PVDDCR_CPU1_P0_TEMP0";
40"PVDDCR_CPU1_P0_TEMP0";
41"PVDDCR_CPU1_P0_PWM4";
42"PVDDCR_CPU1_P0_IMON4";
43"NC_PVDDCR_CPU1_P0_DNC4";
44"PVDDCR_CPU1_P0_VCC3";
45"PVDDCR_CPU1_P0_LSET3";
46"PVDDCR_CPU1_P0_VCCS"CDS_PHYS_NET_NAME"PVCCIN_CPU0_VREF";
47"PVDDCR_CPU1_P0_IMON3";
48"NC_PVDDCR_CPU1_P0_DNC3";
49"NC_PVDDCR_CPU1_P0_GL1_3";
50"NC_PVDDCR_CPU1_P0_GL2_3";
51"SW_PVDDCR_CPU1_P0_SW4_RC";
52"IND_CPU1_P0_CPL3";
53"SW_PVDDCR_CPU1_P0_SW3_RC";
54"PVDDCR_CPU1_P0_VOS3";
55"IND_CPU1_P0_CPL2";
56"IND_CPU1_P0_CPL3";
%"UNIVERSAL_GND"
"1","(1300,875)","0","pure_quanta_power","I1";
;
HDL_POWER"GND"
CDS_LIB"pure_quanta_power";
"A"1;
%"Q_CAP"
"1","(800,1225)","0","pure_quanta","I100";
;
LOCATION"PC113_4"
$SEC"1"
CDS_SEC"1"
PACK_TYPE"0402"
VOLTAGE"25V"
PART_NUMBER"CH4104K1B00"
VALUE"0.1UF"
TOLERANCE"10%"
MATERIAL"X7R"
CDS_LIB"pure_quanta";
"B"
$PN"2"8;
"A"
$PN"1"36;
%"Q_CAP"
"1","(5225,4650)","0","pure_quanta","I101";
;
LOCATION"PC122"
$SEC"1"
CDS_SEC"1"
PACK_TYPE"0402"
TOLERANCE"10%"
MATERIAL"X7R"
VOLTAGE"16V"
VALUE"0.22UF"
PART_NUMBER"CH4223K1B00"
CDS_LIB"pure_quanta";
"B"
$PN"2"17;
"A"
$PN"1"13;
%"Q_RES"
"1","(4500,4775)","0","pure_quanta","I102";
;
LOCATION"PR90"
$SEC"1"
CDS_SEC"1"
PACK_TYPE"0402LF"
WATTAGE"1/16W"
MATERIAL"CHIP"
TOLERANCE"1%"
VALUE"4.7"
PART_NUMBER"CS-4702FB19"
CDS_LIB"pure_quanta";
"B"
$PN"2"13;
"A"
$PN"1"16;
%"Q_CAP"
"1","(5200,1825)","0","pure_quanta","I103";
;
LOCATION"PC121"
$SEC"1"
CDS_SEC"1"
VALUE"0.22UF"
VOLTAGE"16V"
TOLERANCE"10%"
PACK_TYPE"0402"
PART_NUMBER"CH4223K1B00"
MATERIAL"X7R"
CDS_LIB"pure_quanta";
"B"
$PN"2"29;
"A"
$PN"1"11;
%"Q_RES"
"1","(4475,1950)","0","pure_quanta","I104";
;
LOCATION"PR89"
$SEC"1"
CDS_SEC"1"
MATERIAL"CHIP"
WATTAGE"1/16W"
PACK_TYPE"0402LF"
TOLERANCE"1%"
VALUE"4.7"
PART_NUMBER"CS-4702FB19"
CDS_LIB"pure_quanta";
"B"
$PN"2"11;
"A"
$PN"1"34;
%"Q_CAP"
"1","(4075,5375)","0","pure_quanta","I105";
;
LOCATION"PC116_3"
$SEC"1"
CDS_SEC"1"
PACK_TYPE"0402"
VOLTAGE"25V"
PART_NUMBER"CH4104K1B00"
VALUE"0.1UF"
TOLERANCE"10%"
MATERIAL"X7R"
CDS_LIB"pure_quanta";
"B"
$PN"2"14;
"A"
$PN"1"22;
%"Q_CAP"
"1","(4025,2525)","0","pure_quanta","I106";
;
LOCATION"PC115_4"
$SEC"1"
CDS_SEC"1"
PACK_TYPE"0402"
VOLTAGE"25V"
PART_NUMBER"CH4104K1B00"
VALUE"0.1UF"
TOLERANCE"10%"
MATERIAL"X7R"
CDS_LIB"pure_quanta";
"B"
$PN"2"12;
"A"
$PN"1"23;
%"Q_CAP"
"1","(1625,4875)","0","pure_quanta","I107";
;
LOCATION"PC110"
$SEC"1"
CDS_SEC"1"
PACK_TYPE"C0402"
VOLTAGE"10V"
PART_NUMBER"CH5222KEB01"
VALUE"2.2UF"
TOLERANCE"10%"
MATERIAL"X6S"
CDS_LIB"pure_quanta";
"B"
$PN"2"2;
"A"
$PN"1"44;
%"UNIVERSAL_GND"
"1","(1625,4675)","0","pure_quanta_power","I108";
;
HDL_POWER"GND"
CDS_LIB"pure_quanta_power";
"A"2;
%"UNIVERSAL_GND"
"1","(1975,5175)","0","pure_quanta_power","I109";
;
HDL_POWER"GND"
CDS_LIB"pure_quanta_power";
"A"3;
%"UNIVERSAL_GND"
"1","(1325,3700)","0","pure_quanta_power","I11";
;
HDL_POWER"GND"
CDS_LIB"pure_quanta_power";
"A"4;
%"Q_RES"
"2","(1625,5425)","0","pure_quanta","I110";
;
LOCATION"PR88"
$SEC"1"
CDS_SEC"1"
PACK_TYPE"0402LF"
PART_NUMBER"CS-2202FB00"
VALUE"2.2"
TOLERANCE"1%"
MATERIAL"CHIP"
WATTAGE"1/16W"
CDS_LIB"pure_quanta";
"A"
$PN"1"26;
"B"
$PN"2"44;
%"Q_CAP"
"1","(1975,5450)","0","pure_quanta","I111";
;
LOCATION"PC112_C1P0_3"
$SEC"1"
CDS_SEC"1"
PACK_TYPE"C0402"
VOLTAGE"10V"
PART_NUMBER"CH5222KEB01"
VALUE"2.2UF"
TOLERANCE"10%"
MATERIAL"X6S"
CDS_LIB"pure_quanta";
"B"
$PN"2"3;
"A"
$PN"1"26;
%"Q_CAP"
"1","(1450,2050)","0","pure_quanta","I113";
;
LOCATION"PC109"
$SEC"1"
CDS_SEC"1"
PACK_TYPE"C0402"
VOLTAGE"10V"
PART_NUMBER"CH5222KEB01"
VALUE"2.2UF"
TOLERANCE"10%"
MATERIAL"X6S"
CDS_LIB"pure_quanta";
"B"
$PN"2"5;
"A"
$PN"1"35;
%"UNIVERSAL_GND"
"1","(1450,1850)","0","pure_quanta_power","I114";
;
HDL_POWER"GND"
CDS_LIB"pure_quanta_power";
"A"5;
%"UNIVERSAL_GND"
"1","(1800,2350)","0","pure_quanta_power","I115";
;
HDL_POWER"GND"
CDS_LIB"pure_quanta_power";
"A"6;
%"Q_RES"
"2","(1450,2600)","0","pure_quanta","I116";
;
LOCATION"PR87"
$SEC"1"
CDS_SEC"1"
PACK_TYPE"0402LF"
PART_NUMBER"CS-2202FB00"
VALUE"2.2"
TOLERANCE"1%"
MATERIAL"CHIP"
WATTAGE"1/16W"
CDS_LIB"pure_quanta";
"A"
$PN"1"25;
"B"
$PN"2"35;
%"Q_CAP"
"1","(1800,2625)","0","pure_quanta","I117";
;
LOCATION"PC111_C1P0_4"
$SEC"1"
CDS_SEC"1"
PACK_TYPE"C0402"
VOLTAGE"10V"
PART_NUMBER"CH5222KEB01"
VALUE"2.2UF"
TOLERANCE"10%"
MATERIAL"X6S"
CDS_LIB"pure_quanta";
"B"
$PN"2"6;
"A"
$PN"1"25;
%"UNIVERSAL_GND"
"1","(825,3850)","0","pure_quanta_power","I119";
;
HDL_POWER"GND"
CDS_LIB"pure_quanta_power";
"A"7;
%"UNIVERSAL_GND"
"1","(800,1025)","0","pure_quanta_power","I120";
;
HDL_POWER"GND"
CDS_LIB"pure_quanta_power";
"A"8;
%"Q_CAP"
"1","(4625,1425)","0","pure_quanta","I121";
;
LOCATION"PC191"
$SEC"1"
CDS_SEC"1"
PACK_TYPE"C0402"
VOLTAGE"50V"
PART_NUMBER"CH1566K1B09"
VALUE"560PF"
TOLERANCE"10%"
MATERIAL"EMPTY"
CDS_LIB"pure_quanta";
"B"
$PN"2"51;
"A"
$PN"1"30;
%"Q_RES"
"2","(4625,900)","0","pure_quanta","I122";
;
LOCATION"PR509"
$SEC"1"
CDS_SEC"1"
PACK_TYPE"0402LF"
PART_NUMBER"CS-1504FB00"
VALUE"1.5"
TOLERANCE"1%"
MATERIAL"EMPTY"
WATTAGE"1/8W"
CDS_LIB"pure_quanta";
"A"
$PN"1"51;
"B"
$PN"2"9;
%"UNIVERSAL_GND"
"1","(4625,675)","0","pure_quanta_power","I123";
;
HDL_POWER"GND"
CDS_LIB"pure_quanta_power";
"A"9;
%"Q_CAP"
"1","(4675,4225)","0","pure_quanta","I124";
;
LOCATION"PC192"
$SEC"1"
CDS_SEC"1"
PACK_TYPE"C0402"
VOLTAGE"50V"
PART_NUMBER"CH1566K1B09"
VALUE"560PF"
TOLERANCE"10%"
MATERIAL"EMPTY"
CDS_LIB"pure_quanta";
"B"
$PN"2"53;
"A"
$PN"1"15;
%"Q_RES"
"2","(4675,3675)","0","pure_quanta","I125";
;
LOCATION"PR510"
$SEC"1"
CDS_SEC"1"
PACK_TYPE"0402LF"
PART_NUMBER"CS-1504FB00"
VALUE"1.5"
TOLERANCE"1%"
MATERIAL"EMPTY"
WATTAGE"1/8W"
CDS_LIB"pure_quanta";
"A"
$PN"1"53;
"B"
$PN"2"10;
%"UNIVERSAL_GND"
"1","(4675,3450)","0","pure_quanta_power","I126";
;
HDL_POWER"GND"
CDS_LIB"pure_quanta_power";
"A"10;
%"UNIVERSAL_GND"
"1","(6950,1150)","0","pure_quanta_power","I127";
;
HDL_POWER"GND"
CDS_LIB"pure_quanta_power";
"A"27;
%"VCC_CORE"
"1","(1625,5850)","0","pure_quanta_power","I128";
;
HDL_POWER"PVDDCR_CPU1_P0_PVCC"
CDS_LIB"pure_quanta_power";
"A"26;
%"VCC_CORE"
"1","(1450,3025)","0","pure_quanta_power","I129";
;
HDL_POWER"PVDDCR_CPU1_P0_PVCC"
CDS_LIB"pure_quanta_power";
"A"25;
%"ISL99390FRZTR5935"
"1","(3225,1600)","0","pure_quanta","I14";
;
LOCATION"PU14"
$SEC"1"
CDS_SEC"1"
PART_NUMBER"AL099390004"
VALUE"ISL99390FRZ-TR5935"
MATERIAL"IC"
PART_TYPE"SMLF"
CDS_LIB"pure_quanta"
NEEDS_NO_SIZE"TRUE"
CDS_LMAN_SYM_OUTLINE"-300,700,250,-650";
"PGND2"
$PN"7_9-20_24"28;
"GL2"
$PN"41"32;
"GL1"
$PN"6"33;
"DNC"
$PN"31"43;
"EN"
$PN"35"35;
"PGND3"
$PN"40"28;
"VOS"
$PN"1"31;
"VIN2"
$PN"30"23;
"PGND1"
$PN"5"28;
"SW"
$PN"10_19"30;
"LSET"
$PN"37"37;
"IOUT"
$PN"38"42;
"TOUT_FLT"
$PN"36"40;
"PVCC"
$PN"4"25;
"PHASE"
$PN"32"29;
"VIN1"
$PN"25_29"23;
"BOOT"
$PN"33"34;
"AGND"
$PN"2"28;
"VCC"
$PN"3"35;
"REFIN"
$PN"39"36;
"PWM"
$PN"34"41;
%"UNIVERSAL_GND"
"1","(3875,875)","0","pure_quanta_power","I15";
;
HDL_POWER"GND"
CDS_LIB"pure_quanta_power";
"A"28;
%"UNIVERSAL_GND"
"1","(3900,3700)","0","pure_quanta_power","I18";
;
HDL_POWER"GND"
CDS_LIB"pure_quanta_power";
"A"24;
%"Q_RES"
"2","(1325,3925)","2","pure_quanta","I19";
;
LOCATION"PR86"
$SEC"1"
CDS_SEC"1"
PACK_TYPE"0402LF"
PART_NUMBER"CS28872FB01"
VALUE"8.87K"
TOLERANCE"1%"
MATERIAL"EMPTY"
WATTAGE"1/16W"
CDS_LIB"pure_quanta";
"A"
$PN"1"45;
"B"
$PN"2"4;
%"Q_RES"
"2","(1300,1100)","2","pure_quanta","I2";
;
LOCATION"PR85"
$SEC"1"
CDS_SEC"1"
PACK_TYPE"0402LF"
PART_NUMBER"CS28872FB01"
VALUE"8.87K"
TOLERANCE"1%"
MATERIAL"EMPTY"
WATTAGE"1/16W"
CDS_LIB"pure_quanta";
"A"
$PN"1"37;
"B"
$PN"2"1;
%"ISL99390FRZTR5935"
"1","(3250,4425)","0","pure_quanta","I30";
;
LOCATION"PU15"
$SEC"1"
CDS_SEC"1"
PART_NUMBER"AL099390004"
VALUE"ISL99390FRZ-TR5935"
MATERIAL"IC"
PART_TYPE"SMLF"
CDS_LIB"pure_quanta"
NEEDS_NO_SIZE"TRUE"
CDS_LMAN_SYM_OUTLINE"-300,700,250,-650";
"PGND2"
$PN"7_9-20_24"24;
"GL2"
$PN"41"50;
"GL1"
$PN"6"49;
"DNC"
$PN"31"48;
"EN"
$PN"35"44;
"PGND3"
$PN"40"24;
"VOS"
$PN"1"54;
"VIN2"
$PN"30"22;
"PGND1"
$PN"5"24;
"SW"
$PN"10_19"15;
"LSET"
$PN"37"45;
"IOUT"
$PN"38"47;
"TOUT_FLT"
$PN"36"39;
"PVCC"
$PN"4"26;
"PHASE"
$PN"32"17;
"VIN1"
$PN"25_29"22;
"BOOT"
$PN"33"16;
"AGND"
$PN"2"24;
"VCC"
$PN"3"44;
"REFIN"
$PN"39"46;
"PWM"
$PN"34"38;
%"Q_CAP"
"1","(4425,2500)","0","pure_quanta","I37";
;
LOCATION"PC117_4"
$SEC"1"
CDS_SEC"1"
PACK_TYPE"C0402"
VOLTAGE"25V"
VALUE"1UF"
TOLERANCE"10%"
MATERIAL"X6S"
PART_NUMBER"CH5104KEB02"
CDS_LIB"pure_quanta";
"B"
$PN"2"12;
"A"
$PN"1"23;
%"Q_CAP"
"1","(4825,2500)","0","pure_quanta","I38";
;
LOCATION"PC119_4"
$SEC"1"
CDS_SEC"1"
PACK_TYPE"C0805"
VOLTAGE"25V"
VALUE"10UF"
TOLERANCE"10%"
MATERIAL"X6S"
PART_NUMBER"CH6104KEA00"
CDS_LIB"pure_quanta";
"B"
$PN"2"12;
"A"
$PN"1"23;
%"Q_CAP"
"1","(5225,2500)","0","pure_quanta","I40";
;
LOCATION"PC123_4"
$SEC"1"
CDS_SEC"1"
VOLTAGE"25V"
VALUE"10UF"
TOLERANCE"10%"
MATERIAL"X6S"
PACK_TYPE"C0805"
PART_NUMBER"CH6104KEA00"
CDS_LIB"pure_quanta";
"B"
$PN"2"12;
"A"
$PN"1"23;
%"UNIVERSAL_GND"
"1","(5600,2125)","0","pure_quanta_power","I41";
;
HDL_POWER"GND"
CDS_LIB"pure_quanta_power";
"A"12;
%"Q_CAP"
"1","(5600,2500)","0","pure_quanta","I42";
;
LOCATION"PC125_4"
$SEC"1"
CDS_SEC"1"
PACK_TYPE"C0805"
VOLTAGE"25V"
PART_NUMBER"CH6104KEA00"
VALUE"10UF"
TOLERANCE"10%"
MATERIAL"X6S"
CDS_LIB"pure_quanta";
"B"
$PN"2"12;
"A"
$PN"1"23;
%"VCC_CORE"
"1","(5600,2850)","0","pure_quanta_power","I43";
;
HDL_POWER"SW_P12V_STBY_PVDDCR_CPU1_P0_FLT"
CDS_LIB"pure_quanta_power";
"A"23;
%"Q_CAP"
"1","(4475,5350)","0","pure_quanta","I50";
;
LOCATION"PC118_3"
$SEC"1"
CDS_SEC"1"
PACK_TYPE"C0402"
VOLTAGE"25V"
VALUE"1UF"
TOLERANCE"10%"
MATERIAL"X6S"
PART_NUMBER"CH5104KEB02"
CDS_LIB"pure_quanta";
"B"
$PN"2"14;
"A"
$PN"1"22;
%"Q_CAP"
"1","(4875,5350)","0","pure_quanta","I51";
;
LOCATION"PC120_3"
$SEC"1"
CDS_SEC"1"
PACK_TYPE"C0805"
VOLTAGE"25V"
VALUE"10UF"
TOLERANCE"10%"
MATERIAL"X6S"
PART_NUMBER"CH6104KEA00"
CDS_LIB"pure_quanta";
"B"
$PN"2"14;
"A"
$PN"1"22;
%"Q_CAP"
"1","(5275,5350)","0","pure_quanta","I55";
;
LOCATION"PC124_3"
$SEC"1"
CDS_SEC"1"
PACK_TYPE"C0805"
VOLTAGE"25V"
PART_NUMBER"CH6104KEA00"
VALUE"10UF"
TOLERANCE"10%"
MATERIAL"X6S"
CDS_LIB"pure_quanta";
"B"
$PN"2"14;
"A"
$PN"1"22;
%"Q_CAP"
"1","(5650,5350)","0","pure_quanta","I56";
;
LOCATION"PC126_3"
$SEC"1"
CDS_SEC"1"
PACK_TYPE"C0805"
VOLTAGE"25V"
PART_NUMBER"CH6104KEA00"
VALUE"10UF"
TOLERANCE"10%"
MATERIAL"X6S"
CDS_LIB"pure_quanta";
"B"
$PN"2"14;
"A"
$PN"1"22;
%"UNIVERSAL_GND"
"1","(5650,5000)","0","pure_quanta_power","I57";
;
HDL_POWER"GND"
CDS_LIB"pure_quanta_power";
"A"14;
%"VCC_CORE"
"1","(5650,5700)","0","pure_quanta_power","I58";
;
HDL_POWER"SW_P12V_STBY_PVDDCR_CPU1_P0_FLT"
CDS_LIB"pure_quanta_power";
"A"22;
%"Q_RES"
"1","(5825,3325)","0","pure_quanta","I76";
;
LOCATION"PR92"
$SEC"1"
CDS_SEC"1"
PACK_TYPE"0402LF"
PART_NUMBER"CS00002JB38"
VALUE"0"
TOLERANCE"5%"
MATERIAL"CHIP"
WATTAGE"1/16W"
CDS_LIB"pure_quanta";
"B"
$PN"2"21;
"A"
$PN"1"54;
%"VCC_CORE"
"1","(8350,4525)","0","pure_quanta_power","I77";
;
HDL_POWER"PVDDCR_CPU1_P0"
CDS_LIB"pure_quanta_power";
"A"21;
%"Q_CAP"
"1","(8350,4225)","0","pure_quanta","I78";
;
LOCATION"PC130_3"
$SEC"1"
CDS_SEC"1"
PACK_TYPE"0805"
VOLTAGE"4V"
PART_NUMBER"TMP_QCH622KMEA01"
VALUE"22UF"
TOLERANCE"20%"
MATERIAL"X6S"
CDS_LIB"pure_quanta";
"B"
$PN"2"20;
"A"
$PN"1"21;
%"Q_CAP"
"1","(7925,4225)","0","pure_quanta","I79";
;
LOCATION"PC129_3"
$SEC"1"
CDS_SEC"1"
PACK_TYPE"0805"
VOLTAGE"4V"
PART_NUMBER"TMP_QCH622KMEA01"
VALUE"22UF"
TOLERANCE"20%"
MATERIAL"X6S"
CDS_LIB"pure_quanta";
"B"
$PN"2"20;
"A"
$PN"1"21;
%"UNIVERSAL_GND"
"1","(8350,3900)","0","pure_quanta_power","I80";
;
HDL_POWER"GND"
CDS_LIB"pure_quanta_power";
"A"20;
%"Q_RES"
"1","(5825,600)","0","pure_quanta","I92";
;
LOCATION"PR91"
$SEC"1"
CDS_SEC"1"
PACK_TYPE"0402LF"
PART_NUMBER"CS00002JB38"
VALUE"0"
TOLERANCE"5%"
MATERIAL"CHIP"
WATTAGE"1/16W"
CDS_LIB"pure_quanta";
"B"
$PN"2"19;
"A"
$PN"1"31;
%"VCC_CORE"
"1","(7900,1700)","0","pure_quanta_power","I93";
;
HDL_POWER"PVDDCR_CPU1_P0"
CDS_LIB"pure_quanta_power";
"A"19;
%"UNIVERSAL_GND"
"1","(7900,975)","0","pure_quanta_power","I94";
;
HDL_POWER"GND"
CDS_LIB"pure_quanta_power";
"A"18;
%"Q_CAP"
"1","(7900,1400)","0","pure_quanta","I95";
;
LOCATION"PC128_4"
$SEC"1"
CDS_SEC"1"
PACK_TYPE"0805"
VOLTAGE"4V"
PART_NUMBER"TMP_QCH622KMEA01"
VALUE"22UF"
TOLERANCE"20%"
MATERIAL"X6S"
CDS_LIB"pure_quanta";
"B"
$PN"2"18;
"A"
$PN"1"19;
%"Q_CAP"
"1","(7475,1400)","0","pure_quanta","I96";
;
LOCATION"PC127_4"
$SEC"1"
CDS_SEC"1"
PACK_TYPE"0805"
VOLTAGE"4V"
PART_NUMBER"TMP_QCH622KMEA01"
VALUE"22UF"
TOLERANCE"20%"
MATERIAL"X6S"
CDS_LIB"pure_quanta";
"B"
$PN"2"18;
"A"
$PN"1"19;
%"Q_INDUCTOR4P_14"
"1","(6125,1475)","0","pure_quanta","I97";
;
LOCATION"PL13"
$SEC"1"
CDS_SEC"1"
PART_NUMBER"CV+15^0TZ04"
VALUE"150NH"
MATERIAL"IND"
PART_TYPE"SMLF"
CDS_LIB"pure_quanta"
NEEDS_NO_SIZE"TRUE";
"1"
$PN"1"30;
"4"
$PN"4"19;
"3"
$PN"3"27;
"2"
$PN"2"52;
%"Q_INDUCTOR4P_14"
"1","(6450,4300)","0","pure_quanta","I98";
;
LOCATION"PL14"
$SEC"1"
CDS_SEC"1"
PART_NUMBER"CV+15^0TZ04"
VALUE"150NH"
MATERIAL"IND"
PART_TYPE"SMLF"
NEEDS_NO_SIZE"TRUE"
CDS_LIB"pure_quanta";
"1"
$PN"1"15;
"4"
$PN"4"21;
"3"
$PN"3"56;
"2"
$PN"2"55;
%"Q_CAP"
"1","(825,4050)","0","pure_quanta","I99";
;
LOCATION"PC114_3"
$SEC"1"
CDS_SEC"1"
PACK_TYPE"0402"
VOLTAGE"25V"
PART_NUMBER"CH4104K1B00"
VALUE"0.1UF"
TOLERANCE"10%"
MATERIAL"X7R"
CDS_LIB"pure_quanta";
"B"
$PN"2"7;
"A"
$PN"1"46;
END.
